# T6G (Grand Teton) — schematic netlist excerpt (pin names and nets, part order shuffled) for the footprints in the layout excerpt that follows; sources: Cadence DE-HDL packaged netlist, KiCad conversion of 04192023_DAF0TMB3IC0_F0TG_MB_C_brd_V02_OCP.brd

PU3  MPQ8633BGLEC838Z  MPQ8633BGLE-C838-Z IC  pkg QFN14_4X3  page 226
  BST  = SW_PVDD18_S5_P1_BST
  AGND  = GND
  CS  = PVDD18_S5_P1_CS
  MODE  = PVDD18_S5_P1_MODE
  TRK_REF  = PVDD18_S5_P1_REF
  RGND  = PVDD18_SS_P1_RGND
  FB  = PVDD18_S5_P1_FB
  EN  = PVDD18_S5_P1_EN
  PGOOD  = PWRGD_PVDD18_S5_P1
  VIN1  = SW_P12V_AUX_PVDD18_S5_P1_FLT
  PGND  = GND
  VCC  = PVDD18_S5_P1_VCC
  SW  = SW_PVDD18_S5_P1_SW
  VIN2  = SW_P12V_AUX_PVDD18_S5_P1_FLT

C1880  Q_CAP  0.1UF 25V 10% X7R  pkg 0402  page 143 : A = P3V3_AUX ; B = GND

(kicad_pcb
	(version 20260206)
	(generator "pcbnew")
	(generator_version "10.0")
	(general
		(thickness 1.6)
		(legacy_teardrops no)
	)
	(paper "A4")
	(title_block
		(title "04192023_DAF0TMB3IC0_F0TG_MB_C_brd_V02_OCP.brd")
		(comment 1 "Grand Teton / footprints 1118-1119 of 8354")
	)
	(layers
		(0 "F.Cu" signal "TOP")
		(4 "In1.Cu" signal "GND")
		(6 "In2.Cu" signal "IN1")
		(8 "In3.Cu" signal "GND1")
		(10 "In4.Cu" signal "IN2")
		(12 "In5.Cu" signal "GND2")
		(14 "In6.Cu" signal "IN3")
		(16 "In7.Cu" signal "GND3")
		(18 "In8.Cu" signal "VCC")
		(20 "In9.Cu" signal "VCC1")
		(22 "In10.Cu" signal "GND4")
		(24 "In11.Cu" signal "IN4")
		(26 "In12.Cu" signal "GND5")
		(28 "In13.Cu" signal "IN5")
		(30 "In14.Cu" signal "GND6")
		(32 "In15.Cu" signal "IN6")
		(34 "In16.Cu" signal "GND7")
		(2 "B.Cu" signal "BOTTOM")
		(9 "F.Adhes" user "F.Adhesive")
		(11 "B.Adhes" user "B.Adhesive")
		(13 "F.Paste" user "Package Geometry/Pastemask Top")
		(15 "B.Paste" user "Package Geometry/Pastemask Bottom")
		(5 "F.SilkS" user "Ref Des/Silkscreen Top")
		(7 "B.SilkS" user "Ref Des/Silkscreen Bottom")
		(1 "F.Mask" user "Board Geometry/Soldermask Top")
		(3 "B.Mask" user "Board Geometry/Soldermask Bottom")
		(17 "Dwgs.User" user "User.Drawings")
		(19 "Cmts.User" user "User.Comments")
		(21 "Eco1.User" user "User.Eco1")
		(23 "Eco2.User" user "User.Eco2")
		(25 "Edge.Cuts" user "Board Geometry/Outline")
		(27 "Margin" user)
		(31 "F.CrtYd" user "Package Geometry/Place Bound Top")
		(29 "B.CrtYd" user "Package Geometry/Place Bound Bottom")
		(35 "F.Fab" user "Ref Des/Assembly Top")
		(33 "B.Fab" user "Ref Des/Assembly Bottom")
	)
	(footprint ""
		(layer "F.Cu")
		(at 69.85127 -152.33269 90)
		(property "Reference" "PU3"
			(at 4.542536 -1.890014 0)
			(unlocked yes)
			(layer "F.SilkS")
			(effects
				(font
					(size 0.7874 0.5842)
					(thickness 0.1524)
				)
				(justify left)
			)
		)
		(property "Value" ""
			(at 0 0 90)
			(layer "F.Fab")
			(effects
				(font
					(size 1.27 1.27)
				)
			)
		)
		(duplicate_pad_numbers_are_jumpers no)
		(fp_line
			(start 1.549908 -2.050034)
			(end 0.5842 -2.050034)
			(stroke
				(width 0.1524)
				(type default)
			)
			(layer "F.SilkS")
		)
		(fp_line
			(start -0.5842 -2.050034)
			(end -1.549908 -2.050034)
			(stroke
				(width 0.1524)
				(type default)
			)
			(layer "F.SilkS")
		)
		(fp_line
			(start -1.549908 -2.050034)
			(end -1.549908 -1.9812)
			(stroke
				(width 0.1524)
				(type default)
			)
			(layer "F.SilkS")
		)
		(fp_line
			(start 1.549908 -1.9812)
			(end 1.549908 -2.050034)
			(stroke
				(width 0.1524)
				(type default)
			)
			(layer "F.SilkS")
		)
		(fp_line
			(start -1.549908 1.9812)
			(end -1.549908 2.050034)
			(stroke
				(width 0.1524)
				(type default)
			)
			(layer "F.SilkS")
		)
		(fp_line
			(start 0 2.050034)
			(end 1.549908 2.050034)
			(stroke
				(width 0.1524)
				(type default)
			)
			(layer "F.SilkS")
		)
		(fp_line
			(start -1.549908 2.050034)
			(end -0.5842 2.050034)
			(stroke
				(width 0.1524)
				(type default)
			)
			(layer "F.SilkS")
		)
		(fp_poly
			(pts
				(xy -1.991868 -1.787398) (xy -3.007868 -1.279398) (xy -3.007868 -2.295398)
			)
			(stroke
				(width 0)
				(type default)
			)
			(fill yes)
			(layer "F.SilkS")
		)
		(fp_line
			(start 1.549908 -2.050034)
			(end -1.549908 -2.050034)
			(stroke
				(width 0.1)
				(type default)
			)
			(layer "F.Fab")
		)
		(fp_line
			(start -1.549908 -2.050034)
			(end -1.549908 2.050034)
			(stroke
				(width 0.1)
				(type default)
			)
			(layer "F.Fab")
		)
		(fp_line
			(start 1.549908 2.050034)
			(end 1.549908 -2.050034)
			(stroke
				(width 0.1)
				(type default)
			)
			(layer "F.Fab")
		)
		(fp_line
			(start -1.549908 2.050034)
			(end 1.549908 2.050034)
			(stroke
				(width 0.1)
				(type default)
			)
			(layer "F.Fab")
		)
		(fp_poly
			(pts
				(xy -2.9464 -2.208022) (xy -2.9464 -1.192022) (xy -1.9304 -1.700022)
			)
			(stroke
				(width 0)
				(type default)
			)
			(fill yes)
			(layer "F.Fab")
		)
		(pad "1" smd circle
			(at -1.35001 -1.700022 90)
			(size 0 0)
			(layers "F.Cu" "F.Mask" "F.Paste")
			(net "SW_PVDD18_S5_P1_BST")
		)
		(pad "2" smd rect
			(at -1.400048 -1.199896 180)
			(size 0.1778 0.8128)
			(layers "F.Cu" "F.Mask" "F.Paste")
			(net "GND")
		)
		(pad "3" smd rect
			(at -1.400048 -0.8001 180)
			(size 0.1778 0.8128)
			(layers "F.Cu" "F.Mask" "F.Paste")
			(net "PVDD18_S5_P1_CS")
		)
		(pad "4" smd rect
			(at -1.400048 -0.40005 180)
			(size 0.1778 0.8128)
			(layers "F.Cu" "F.Mask" "F.Paste")
			(net "PVDD18_S5_P1_MODE")
		)
		(pad "5" smd rect
			(at -1.400048 0 180)
			(size 0.1778 0.8128)
			(layers "F.Cu" "F.Mask" "F.Paste")
			(net "PVDD18_S5_P1_REF")
		)
		(pad "6" smd rect
			(at -1.400048 0.40005 180)
			(size 0.1778 0.8128)
			(layers "F.Cu" "F.Mask" "F.Paste")
			(net "PVDD18_SS_P1_RGND")
		)
		(pad "7" smd rect
			(at -1.400048 0.8001 180)
			(size 0.1778 0.8128)
			(layers "F.Cu" "F.Mask" "F.Paste")
			(net "PVDD18_S5_P1_FB")
		)
		(pad "8" smd rect
			(at -1.400048 1.199896 180)
			(size 0.1778 0.8128)
			(layers "F.Cu" "F.Mask" "F.Paste")
			(net "PVDD18_S5_P1_EN")
		)
		(pad "9" smd rect
			(at -1.400048 1.700022 180)
			(size 0.3048 0.8128)
			(layers "F.Cu" "F.Mask" "F.Paste")
			(net "PWRGD_PVDD18_S5_P1")
		)
		(pad "10" smd rect
			(at -0.299974 1.299972 90)
			(size 0.3048 2.0066)
			(layers "F.Cu" "F.Mask" "F.Paste")
			(net "SW_P12V_AUX_PVDD18_S5_P1_FLT")
		)
		(pad "11_18" smd circle
			(at 1.175004 0.275082 90)
			(size 0 0)
			(layers "F.Cu" "F.Mask" "F.Paste")
			(net "GND")
		)
		(pad "19" smd rect
			(at 1.400048 -1.700022)
			(size 0.3048 0.8128)
			(layers "F.Cu" "F.Mask" "F.Paste")
			(net "PVDD18_S5_P1_VCC")
		)
		(pad "20" smd rect
			(at 0.299974 -1.299972 90)
			(size 0.3048 2.0066)
			(layers "F.Cu" "F.Mask" "F.Paste")
			(net "SW_PVDD18_S5_P1_SW")
		)
		(pad "21" smd rect
			(at -0.299974 -1.299972 90)
			(size 0.3048 2.0066)
			(layers "F.Cu" "F.Mask" "F.Paste")
			(net "SW_P12V_AUX_PVDD18_S5_P1_FLT")
		)
	)
	(footprint ""
		(layer "F.Cu")
		(at 147.16379 -98.755708 90)
		(property "Reference" "C1880"
			(at 0 0 90)
			(layer "F.SilkS")
			(hide yes)
			(effects
				(font
					(size 1.27 1.27)
				)
			)
		)
		(property "Value" ""
			(at 0 0 90)
			(layer "F.Fab")
			(effects
				(font
					(size 1.27 1.27)
				)
			)
		)
		(duplicate_pad_numbers_are_jumpers no)
		(fp_line
			(start 0.7874 -0.4064)
			(end 0.7874 0.4064)
			(stroke
				(width 0.1524)
				(type default)
			)
			(layer "F.SilkS")
		)
		(fp_line
			(start -0.7874 -0.4064)
			(end 0.7874 -0.4064)
			(stroke
				(width 0.1524)
				(type default)
			)
			(layer "F.SilkS")
		)
		(fp_line
			(start 0.7874 0.4064)
			(end -0.7874 0.4064)
			(stroke
				(width 0.1524)
				(type default)
			)
			(layer "F.SilkS")
		)
		(fp_line
			(start -0.7874 0.4064)
			(end -0.7874 -0.4064)
			(stroke
				(width 0.1524)
				(type default)
			)
			(layer "F.SilkS")
		)
		(fp_line
			(start -0.12065 -0.305054)
			(end -0.12065 -0.2794)
			(stroke
				(width 0.1)
				(type default)
			)
			(layer "F.Fab")
		)
		(fp_line
			(start -0.67945 -0.305054)
			(end -0.12065 -0.305054)
			(stroke
				(width 0.1)
				(type default)
			)
			(layer "F.Fab")
		)
		(fp_line
			(start 0.67945 -0.3048)
			(end 0.67945 0.3048)
			(stroke
				(width 0.1)
				(type default)
			)
			(layer "F.Fab")
		)
		(fp_line
			(start 0.12065 -0.3048)
			(end 0.67945 -0.3048)
			(stroke
				(width 0.1)
				(type default)
			)
			(layer "F.Fab")
		)
		(fp_line
			(start 0.12065 -0.2794)
			(end 0.12065 -0.3048)
			(stroke
				(width 0.1)
				(type default)
			)
			(layer "F.Fab")
		)
		(fp_line
			(start -0.12065 -0.2794)
			(end 0.12065 -0.2794)
			(stroke
				(width 0.1)
				(type default)
			)
			(layer "F.Fab")
		)
		(fp_line
			(start 0.120396 0.2794)
			(end -0.12065 0.2794)
			(stroke
				(width 0.1)
				(type default)
			)
			(layer "F.Fab")
		)
		(fp_line
			(start -0.12065 0.2794)
			(end -0.12065 0.3048)
			(stroke
				(width 0.1)
				(type default)
			)
			(layer "F.Fab")
		)
		(fp_line
			(start 0.67945 0.3048)
			(end 0.120396 0.3048)
			(stroke
				(width 0.1)
				(type default)
			)
			(layer "F.Fab")
		)
		(fp_line
			(start 0.120396 0.3048)
			(end 0.120396 0.2794)
			(stroke
				(width 0.1)
				(type default)
			)
			(layer "F.Fab")
		)
		(fp_line
			(start -0.12065 0.3048)
			(end -0.67945 0.3048)
			(stroke
				(width 0.1)
				(type default)
			)
			(layer "F.Fab")
		)
		(fp_line
			(start -0.67945 0.3048)
			(end -0.67945 -0.305054)
			(stroke
				(width 0.1)
				(type default)
			)
			(layer "F.Fab")
		)
		(pad "1" smd circle
			(at -0.40005 0 90)
			(size 0 0)
			(layers "F.Cu" "F.Mask" "F.Paste")
			(net "P3V3_AUX")
		)
		(pad "2" smd circle
			(at 0.40005 0 90)
			(size 0 0)
			(layers "F.Cu" "F.Mask" "F.Paste")
			(net "GND")
		)
	)
)
